(kicad_pcb
	(version 20260206)
	(generator "pcbnew")
	(generator_version "10.0")
	(general
		(thickness 1.6)
		(legacy_teardrops no)
	)
	(paper "A4")
	(title_block
		(title "03242023_DA0F0TMBIJ0_F0T_Motherboard_J_brd_V01_OCP.brd")
		(comment 1 "Grand Teton / footprints 5518-5525 of 6105")
	)
	(layers
		(0 "F.Cu" signal "TOP")
		(4 "In1.Cu" signal "GND")
		(6 "In2.Cu" signal "IN1")
		(8 "In3.Cu" signal "GND1")
		(10 "In4.Cu" signal "IN2")
		(12 "In5.Cu" signal "GND2")
		(14 "In6.Cu" signal "IN3")
		(16 "In7.Cu" signal "GND3")
		(18 "In8.Cu" signal "VCC")
		(20 "In9.Cu" signal "VCC1")
		(22 "In10.Cu" signal "GND4")
		(24 "In11.Cu" signal "IN4")
		(26 "In12.Cu" signal "GND5")
		(28 "In13.Cu" signal "IN5")
		(30 "In14.Cu" signal "GND6")
		(32 "In15.Cu" signal "IN6")
		(34 "In16.Cu" signal "GND7")
		(2 "B.Cu" signal "BOTTOM")
		(9 "F.Adhes" user "F.Adhesive")
		(11 "B.Adhes" user "B.Adhesive")
		(13 "F.Paste" user "Package Geometry/Pastemask Top")
		(15 "B.Paste" user "Package Geometry/Pastemask Bottom")
		(5 "F.SilkS" user "Ref Des/Silkscreen Top")
		(7 "B.SilkS" user "Ref Des/Silkscreen Bottom")
		(1 "F.Mask" user "Board Geometry/Soldermask Top")
		(3 "B.Mask" user "Board Geometry/Soldermask Bottom")
		(17 "Dwgs.User" user "User.Drawings")
		(19 "Cmts.User" user "User.Comments")
		(21 "Eco1.User" user "User.Eco1")
		(23 "Eco2.User" user "User.Eco2")
		(25 "Edge.Cuts" user "Board Geometry/Outline")
		(27 "Margin" user)
		(31 "F.CrtYd" user "Package Geometry/Place Bound Top")
		(29 "B.CrtYd" user "Package Geometry/Place Bound Bottom")
		(35 "F.Fab" user "Ref Des/Assembly Top")
		(33 "B.Fab" user "Ref Des/Assembly Bottom")
	)
	(footprint ""
		(layer "B.Cu")
		(at 317.756032 -39.358062 -135)
		(property "Reference" "R697"
			(at 0 0 45)
			(layer "B.SilkS")
			(hide yes)
			(effects
				(font
					(size 1.27 1.27)
				)
				(justify mirror)
			)
		)
		(property "Value" ""
			(at 0 0 45)
			(layer "B.Fab")
			(effects
				(font
					(size 1.27 1.27)
				)
				(justify mirror)
			)
		)
		(duplicate_pad_numbers_are_jumpers no)
		(fp_line
			(start 0.787389 0.406267)
			(end 0.787389 -0.406267)
			(stroke
				(width 0.1524)
				(type default)
			)
			(layer "B.SilkS")
		)
		(fp_line
			(start 0.787389 -0.406267)
			(end -0.787389 -0.406267)
			(stroke
				(width 0.1524)
				(type default)
			)
			(layer "B.SilkS")
		)
		(fp_line
			(start -0.787389 0.406267)
			(end 0.787389 0.406267)
			(stroke
				(width 0.1524)
				(type default)
			)
			(layer "B.SilkS")
		)
		(fp_line
			(start -0.787389 -0.406267)
			(end -0.787389 0.406267)
			(stroke
				(width 0.1524)
				(type default)
			)
			(layer "B.SilkS")
		)
		(fp_line
			(start 0.679446 0.30479)
			(end 0.679446 -0.305149)
			(stroke
				(width 0.1)
				(type default)
			)
			(layer "B.Fab")
		)
		(fp_line
			(start 0.120515 0.30479)
			(end 0.679446 0.30479)
			(stroke
				(width 0.1)
				(type default)
			)
			(layer "B.Fab")
		)
		(fp_line
			(start 0.120695 0.279466)
			(end 0.120515 0.30479)
			(stroke
				(width 0.1)
				(type default)
			)
			(layer "B.Fab")
		)
		(fp_line
			(start 0.679446 -0.305149)
			(end 0.120695 -0.304969)
			(stroke
				(width 0.1)
				(type default)
			)
			(layer "B.Fab")
		)
		(fp_line
			(start -0.120515 0.30479)
			(end -0.120335 0.279466)
			(stroke
				(width 0.1)
				(type default)
			)
			(layer "B.Fab")
		)
		(fp_line
			(start -0.120335 0.279466)
			(end 0.120695 0.279466)
			(stroke
				(width 0.1)
				(type default)
			)
			(layer "B.Fab")
		)
		(fp_line
			(start 0.120695 -0.279466)
			(end -0.120695 -0.279466)
			(stroke
				(width 0.1)
				(type default)
			)
			(layer "B.Fab")
		)
		(fp_line
			(start 0.120695 -0.304969)
			(end 0.120695 -0.279466)
			(stroke
				(width 0.1)
				(type default)
			)
			(layer "B.Fab")
		)
		(fp_line
			(start -0.679446 0.30479)
			(end -0.120515 0.30479)
			(stroke
				(width 0.1)
				(type default)
			)
			(layer "B.Fab")
		)
		(fp_line
			(start -0.120695 -0.279466)
			(end -0.120515 -0.30479)
			(stroke
				(width 0.1)
				(type default)
			)
			(layer "B.Fab")
		)
		(fp_line
			(start -0.120515 -0.30479)
			(end -0.679446 -0.30479)
			(stroke
				(width 0.1)
				(type default)
			)
			(layer "B.Fab")
		)
		(fp_line
			(start -0.679446 -0.30479)
			(end -0.679446 0.30479)
			(stroke
				(width 0.1)
				(type default)
			)
			(layer "B.Fab")
		)
		(pad "1" smd circle
			(at 0.40005 0 45)
			(size 0 0)
			(layers "B.Cu" "B.Mask" "B.Paste")
			(net "FM_BMC_RSTBTN_OUT_N")
		)
		(pad "2" smd circle
			(at -0.40005 0 45)
			(size 0 0)
			(layers "B.Cu" "B.Mask" "B.Paste")
			(net "RST_PCH_RSTBTN_R_N")
		)
	)
	(footprint ""
		(layer "B.Cu")
		(at 8.19277 -112.04702)
		(property "Reference" "C5232"
			(at 0 0 0)
			(layer "B.SilkS")
			(hide yes)
			(effects
				(font
					(size 1.27 1.27)
				)
				(justify mirror)
			)
		)
		(property "Value" ""
			(at 0 0 0)
			(layer "B.Fab")
			(effects
				(font
					(size 1.27 1.27)
				)
				(justify mirror)
			)
		)
		(duplicate_pad_numbers_are_jumpers no)
		(fp_line
			(start -0.7874 -0.4064)
			(end -0.7874 0.4064)
			(stroke
				(width 0.1524)
				(type default)
			)
			(layer "B.SilkS")
		)
		(fp_line
			(start -0.7874 0.4064)
			(end 0.7874 0.4064)
			(stroke
				(width 0.1524)
				(type default)
			)
			(layer "B.SilkS")
		)
		(fp_line
			(start 0.7874 -0.4064)
			(end -0.7874 -0.4064)
			(stroke
				(width 0.1524)
				(type default)
			)
			(layer "B.SilkS")
		)
		(fp_line
			(start 0.7874 0.4064)
			(end 0.7874 -0.4064)
			(stroke
				(width 0.1524)
				(type default)
			)
			(layer "B.SilkS")
		)
		(fp_line
			(start -0.67945 -0.3048)
			(end -0.67945 0.3048)
			(stroke
				(width 0.1)
				(type default)
			)
			(layer "B.Fab")
		)
		(fp_line
			(start -0.67945 0.3048)
			(end -0.120396 0.3048)
			(stroke
				(width 0.1)
				(type default)
			)
			(layer "B.Fab")
		)
		(fp_line
			(start -0.12065 -0.3048)
			(end -0.67945 -0.3048)
			(stroke
				(width 0.1)
				(type default)
			)
			(layer "B.Fab")
		)
		(fp_line
			(start -0.12065 -0.2794)
			(end -0.12065 -0.3048)
			(stroke
				(width 0.1)
				(type default)
			)
			(layer "B.Fab")
		)
		(fp_line
			(start -0.120396 0.2794)
			(end 0.12065 0.2794)
			(stroke
				(width 0.1)
				(type default)
			)
			(layer "B.Fab")
		)
		(fp_line
			(start -0.120396 0.3048)
			(end -0.120396 0.2794)
			(stroke
				(width 0.1)
				(type default)
			)
			(layer "B.Fab")
		)
		(fp_line
			(start 0.12065 -0.305054)
			(end 0.12065 -0.2794)
			(stroke
				(width 0.1)
				(type default)
			)
			(layer "B.Fab")
		)
		(fp_line
			(start 0.12065 -0.2794)
			(end -0.12065 -0.2794)
			(stroke
				(width 0.1)
				(type default)
			)
			(layer "B.Fab")
		)
		(fp_line
			(start 0.12065 0.2794)
			(end 0.12065 0.3048)
			(stroke
				(width 0.1)
				(type default)
			)
			(layer "B.Fab")
		)
		(fp_line
			(start 0.12065 0.3048)
			(end 0.67945 0.3048)
			(stroke
				(width 0.1)
				(type default)
			)
			(layer "B.Fab")
		)
		(fp_line
			(start 0.67945 -0.305054)
			(end 0.12065 -0.305054)
			(stroke
				(width 0.1)
				(type default)
			)
			(layer "B.Fab")
		)
		(fp_line
			(start 0.67945 0.3048)
			(end 0.67945 -0.305054)
			(stroke
				(width 0.1)
				(type default)
			)
			(layer "B.Fab")
		)
		(pad "1" smd circle
			(at 0.40005 0 180)
			(size 0 0)
			(layers "B.Cu" "B.Mask" "B.Paste")
			(net "PD_U5201_RSTN")
		)
		(pad "2" smd circle
			(at -0.40005 0 180)
			(size 0 0)
			(layers "B.Cu" "B.Mask" "B.Paste")
			(net "GND")
		)
	)
	(footprint ""
		(layer "B.Cu")
		(at 369.52174 -212.049614 180)
		(property "Reference" "C531"
			(at 0 0 0)
			(layer "B.SilkS")
			(hide yes)
			(effects
				(font
					(size 1.27 1.27)
				)
				(justify mirror)
			)
		)
		(property "Value" ""
			(at 0 0 0)
			(layer "B.Fab")
			(effects
				(font
					(size 1.27 1.27)
				)
				(justify mirror)
			)
		)
		(duplicate_pad_numbers_are_jumpers no)
		(fp_line
			(start 1.524 0.762)
			(end 1.524 -0.762)
			(stroke
				(width 0.1524)
				(type default)
			)
			(layer "B.SilkS")
		)
		(fp_line
			(start 1.524 -0.762)
			(end -1.524 -0.762)
			(stroke
				(width 0.1524)
				(type default)
			)
			(layer "B.SilkS")
		)
		(fp_line
			(start -1.524 0.762)
			(end 1.524 0.762)
			(stroke
				(width 0.1524)
				(type default)
			)
			(layer "B.SilkS")
		)
		(fp_line
			(start -1.524 -0.762)
			(end -1.524 0.762)
			(stroke
				(width 0.1524)
				(type default)
			)
			(layer "B.SilkS")
		)
		(fp_line
			(start 1.1049 0.724916)
			(end -1.1049 0.724916)
			(stroke
				(width 0.1)
				(type default)
			)
			(layer "B.Fab")
		)
		(fp_line
			(start 1.1049 -0.724916)
			(end 1.1049 0.724916)
			(stroke
				(width 0.1)
				(type default)
			)
			(layer "B.Fab")
		)
		(fp_line
			(start -1.1049 0.724916)
			(end -1.1049 -0.724916)
			(stroke
				(width 0.1)
				(type default)
			)
			(layer "B.Fab")
		)
		(fp_line
			(start -1.1049 -0.724916)
			(end 1.1049 -0.724916)
			(stroke
				(width 0.1)
				(type default)
			)
			(layer "B.Fab")
		)
		(pad "1" smd rect
			(at 0.889 0 180)
			(size 1.016 1.27)
			(layers "B.Cu" "B.Mask" "B.Paste")
			(net "PVCCINFAON_CPU0")
		)
		(pad "2" smd rect
			(at -0.889 0 180)
			(size 1.016 1.27)
			(layers "B.Cu" "B.Mask" "B.Paste")
			(net "GND")
		)
	)
	(footprint ""
		(layer "B.Cu")
		(at 143.748252 -334.334866)
		(property "Reference" "C1437"
			(at 0 0 0)
			(layer "B.SilkS")
			(hide yes)
			(effects
				(font
					(size 1.27 1.27)
				)
				(justify mirror)
			)
		)
		(property "Value" ""
			(at 0 0 0)
			(layer "B.Fab")
			(effects
				(font
					(size 1.27 1.27)
				)
				(justify mirror)
			)
		)
		(duplicate_pad_numbers_are_jumpers no)
		(fp_line
			(start -0.299974 -0.150114)
			(end -0.299974 0.150114)
			(stroke
				(width 0.1)
				(type default)
			)
			(layer "B.Fab")
		)
		(fp_line
			(start -0.299974 0.150114)
			(end 0.299974 0.150114)
			(stroke
				(width 0.1)
				(type default)
			)
			(layer "B.Fab")
		)
		(fp_line
			(start 0.299974 -0.150114)
			(end -0.299974 -0.150114)
			(stroke
				(width 0.1)
				(type default)
			)
			(layer "B.Fab")
		)
		(fp_line
			(start 0.299974 0.150114)
			(end 0.299974 -0.150114)
			(stroke
				(width 0.1)
				(type default)
			)
			(layer "B.Fab")
		)
		(pad "1" smd rect
			(at 0.2667 0 180)
			(size 0.3048 0.381)
			(layers "B.Cu" "B.Mask" "B.Paste")
			(net "PVPP_HBM_CPU1")
		)
		(pad "2" smd rect
			(at -0.2667 0 180)
			(size 0.3048 0.381)
			(layers "B.Cu" "B.Mask" "B.Paste")
			(net "GND")
		)
	)
	(footprint ""
		(layer "B.Cu")
		(at 438.686956 -318.603376)
		(property "Reference" "R39"
			(at 0 0 0)
			(layer "B.SilkS")
			(hide yes)
			(effects
				(font
					(size 1.27 1.27)
				)
				(justify mirror)
			)
		)
		(property "Value" ""
			(at 0 0 0)
			(layer "B.Fab")
			(effects
				(font
					(size 1.27 1.27)
				)
				(justify mirror)
			)
		)
		(duplicate_pad_numbers_are_jumpers no)
		(fp_line
			(start -0.7874 -0.4064)
			(end -0.7874 0.4064)
			(stroke
				(width 0.1524)
				(type default)
			)
			(layer "B.SilkS")
		)
		(fp_line
			(start -0.7874 0.4064)
			(end 0.7874 0.4064)
			(stroke
				(width 0.1524)
				(type default)
			)
			(layer "B.SilkS")
		)
		(fp_line
			(start 0.7874 -0.4064)
			(end -0.7874 -0.4064)
			(stroke
				(width 0.1524)
				(type default)
			)
			(layer "B.SilkS")
		)
		(fp_line
			(start 0.7874 0.4064)
			(end 0.7874 -0.4064)
			(stroke
				(width 0.1524)
				(type default)
			)
			(layer "B.SilkS")
		)
		(fp_line
			(start -0.67945 -0.3048)
			(end -0.67945 0.3048)
			(stroke
				(width 0.1)
				(type default)
			)
			(layer "B.Fab")
		)
		(fp_line
			(start -0.67945 0.3048)
			(end -0.120396 0.3048)
			(stroke
				(width 0.1)
				(type default)
			)
			(layer "B.Fab")
		)
		(fp_line
			(start -0.12065 -0.3048)
			(end -0.67945 -0.3048)
			(stroke
				(width 0.1)
				(type default)
			)
			(layer "B.Fab")
		)
		(fp_line
			(start -0.12065 -0.2794)
			(end -0.12065 -0.3048)
			(stroke
				(width 0.1)
				(type default)
			)
			(layer "B.Fab")
		)
		(fp_line
			(start -0.120396 0.2794)
			(end 0.12065 0.2794)
			(stroke
				(width 0.1)
				(type default)
			)
			(layer "B.Fab")
		)
		(fp_line
			(start -0.120396 0.3048)
			(end -0.120396 0.2794)
			(stroke
				(width 0.1)
				(type default)
			)
			(layer "B.Fab")
		)
		(fp_line
			(start 0.12065 -0.305054)
			(end 0.12065 -0.2794)
			(stroke
				(width 0.1)
				(type default)
			)
			(layer "B.Fab")
		)
		(fp_line
			(start 0.12065 -0.2794)
			(end -0.12065 -0.2794)
			(stroke
				(width 0.1)
				(type default)
			)
			(layer "B.Fab")
		)
		(fp_line
			(start 0.12065 0.2794)
			(end 0.12065 0.3048)
			(stroke
				(width 0.1)
				(type default)
			)
			(layer "B.Fab")
		)
		(fp_line
			(start 0.12065 0.3048)
			(end 0.67945 0.3048)
			(stroke
				(width 0.1)
				(type default)
			)
			(layer "B.Fab")
		)
		(fp_line
			(start 0.67945 -0.305054)
			(end 0.12065 -0.305054)
			(stroke
				(width 0.1)
				(type default)
			)
			(layer "B.Fab")
		)
		(fp_line
			(start 0.67945 0.3048)
			(end 0.67945 -0.305054)
			(stroke
				(width 0.1)
				(type default)
			)
			(layer "B.Fab")
		)
		(pad "1" smd circle
			(at 0.40005 0 180)
			(size 0 0)
			(layers "B.Cu" "B.Mask" "B.Paste")
			(net "PD_CHG_CPU0_DIMM2_SAA")
		)
		(pad "2" smd circle
			(at -0.40005 0 180)
			(size 0 0)
			(layers "B.Cu" "B.Mask" "B.Paste")
			(net "GND")
		)
	)
	(footprint ""
		(layer "B.Cu")
		(at 115.195604 -296.05478 180)
		(property "Reference" "C350"
			(at 0 0 0)
			(layer "B.SilkS")
			(hide yes)
			(effects
				(font
					(size 1.27 1.27)
				)
				(justify mirror)
			)
		)
		(property "Value" ""
			(at 0 0 0)
			(layer "B.Fab")
			(effects
				(font
					(size 1.27 1.27)
				)
				(justify mirror)
			)
		)
		(duplicate_pad_numbers_are_jumpers no)
		(fp_line
			(start 1.524 0.762)
			(end 1.524 -0.762)
			(stroke
				(width 0.1524)
				(type default)
			)
			(layer "B.SilkS")
		)
		(fp_line
			(start 1.524 -0.762)
			(end -1.524 -0.762)
			(stroke
				(width 0.1524)
				(type default)
			)
			(layer "B.SilkS")
		)
		(fp_line
			(start -1.524 0.762)
			(end 1.524 0.762)
			(stroke
				(width 0.1524)
				(type default)
			)
			(layer "B.SilkS")
		)
		(fp_line
			(start -1.524 -0.762)
			(end -1.524 0.762)
			(stroke
				(width 0.1524)
				(type default)
			)
			(layer "B.SilkS")
		)
		(fp_line
			(start 1.1049 0.724916)
			(end -1.1049 0.724916)
			(stroke
				(width 0.1)
				(type default)
			)
			(layer "B.Fab")
		)
		(fp_line
			(start 1.1049 -0.724916)
			(end 1.1049 0.724916)
			(stroke
				(width 0.1)
				(type default)
			)
			(layer "B.Fab")
		)
		(fp_line
			(start -1.1049 0.724916)
			(end -1.1049 -0.724916)
			(stroke
				(width 0.1)
				(type default)
			)
			(layer "B.Fab")
		)
		(fp_line
			(start -1.1049 -0.724916)
			(end 1.1049 -0.724916)
			(stroke
				(width 0.1)
				(type default)
			)
			(layer "B.Fab")
		)
		(pad "1" smd rect
			(at 0.889 0 180)
			(size 1.016 1.27)
			(layers "B.Cu" "B.Mask" "B.Paste")
			(net "PVCCIN_CPU1")
		)
		(pad "2" smd rect
			(at -0.889 0 180)
			(size 1.016 1.27)
			(layers "B.Cu" "B.Mask" "B.Paste")
			(net "GND")
		)
	)
	(footprint ""
		(layer "B.Cu")
		(at 200.608946 -321.554856 -90)
		(property "Reference" "C83"
			(at 0 0 90)
			(layer "B.SilkS")
			(hide yes)
			(effects
				(font
					(size 1.27 1.27)
				)
				(justify mirror)
			)
		)
		(property "Value" ""
			(at 0 0 90)
			(layer "B.Fab")
			(effects
				(font
					(size 1.27 1.27)
				)
				(justify mirror)
			)
		)
		(duplicate_pad_numbers_are_jumpers no)
		(fp_line
			(start -1.524 0.762)
			(end 1.524 0.762)
			(stroke
				(width 0.1524)
				(type default)
			)
			(layer "B.SilkS")
		)
		(fp_line
			(start 1.524 0.762)
			(end 1.524 -0.762)
			(stroke
				(width 0.1524)
				(type default)
			)
			(layer "B.SilkS")
		)
		(fp_line
			(start -1.524 -0.762)
			(end -1.524 0.762)
			(stroke
				(width 0.1524)
				(type default)
			)
			(layer "B.SilkS")
		)
		(fp_line
			(start 1.524 -0.762)
			(end -1.524 -0.762)
			(stroke
				(width 0.1524)
				(type default)
			)
			(layer "B.SilkS")
		)
		(fp_line
			(start -1.1049 0.724916)
			(end -1.1049 -0.724916)
			(stroke
				(width 0.1)
				(type default)
			)
			(layer "B.Fab")
		)
		(fp_line
			(start 1.1049 0.724916)
			(end -1.1049 0.724916)
			(stroke
				(width 0.1)
				(type default)
			)
			(layer "B.Fab")
		)
		(fp_line
			(start -1.1049 -0.724916)
			(end 1.1049 -0.724916)
			(stroke
				(width 0.1)
				(type default)
			)
			(layer "B.Fab")
		)
		(fp_line
			(start 1.1049 -0.724916)
			(end 1.1049 0.724916)
			(stroke
				(width 0.1)
				(type default)
			)
			(layer "B.Fab")
		)
		(pad "1" smd rect
			(at 0.889 0 270)
			(size 1.016 1.27)
			(layers "B.Cu" "B.Mask" "B.Paste")
			(net "P12V_S3_AUX_CPU1_NVDIMM")
		)
		(pad "2" smd rect
			(at -0.889 0 270)
			(size 1.016 1.27)
			(layers "B.Cu" "B.Mask" "B.Paste")
			(net "GND")
		)
	)
	(footprint ""
		(layer "B.Cu")
		(at 69.772022 -318.385444 90)
		(property "Reference" "R2502"
			(at 0 0 90)
			(layer "B.SilkS")
			(hide yes)
			(effects
				(font
					(size 1.27 1.27)
				)
				(justify mirror)
			)
		)
		(property "Value" ""
			(at 0 0 90)
			(layer "B.Fab")
			(effects
				(font
					(size 1.27 1.27)
				)
				(justify mirror)
			)
		)
		(duplicate_pad_numbers_are_jumpers no)
		(fp_line
			(start 0.7874 -0.4064)
			(end -0.7874 -0.4064)
			(stroke
				(width 0.1524)
				(type default)
			)
			(layer "B.SilkS")
		)
		(fp_line
			(start -0.7874 -0.4064)
			(end -0.7874 0.4064)
			(stroke
				(width 0.1524)
				(type default)
			)
			(layer "B.SilkS")
		)
		(fp_line
			(start 0.7874 0.4064)
			(end 0.7874 -0.4064)
			(stroke
				(width 0.1524)
				(type default)
			)
			(layer "B.SilkS")
		)
		(fp_line
			(start -0.7874 0.4064)
			(end 0.7874 0.4064)
			(stroke
				(width 0.1524)
				(type default)
			)
			(layer "B.SilkS")
		)
		(fp_line
			(start 0.67945 -0.305054)
			(end 0.12065 -0.305054)
			(stroke
				(width 0.1)
				(type default)
			)
			(layer "B.Fab")
		)
		(fp_line
			(start 0.12065 -0.305054)
			(end 0.12065 -0.2794)
			(stroke
				(width 0.1)
				(type default)
			)
			(layer "B.Fab")
		)
		(fp_line
			(start -0.12065 -0.3048)
			(end -0.67945 -0.3048)
			(stroke
				(width 0.1)
				(type default)
			)
			(layer "B.Fab")
		)
		(fp_line
			(start -0.67945 -0.3048)
			(end -0.67945 0.3048)
			(stroke
				(width 0.1)
				(type default)
			)
			(layer "B.Fab")
		)
		(fp_line
			(start 0.12065 -0.2794)
			(end -0.12065 -0.2794)
			(stroke
				(width 0.1)
				(type default)
			)
			(layer "B.Fab")
		)
		(fp_line
			(start -0.12065 -0.2794)
			(end -0.12065 -0.3048)
			(stroke
				(width 0.1)
				(type default)
			)
			(layer "B.Fab")
		)
		(fp_line
			(start 0.12065 0.2794)
			(end 0.12065 0.3048)
			(stroke
				(width 0.1)
				(type default)
			)
			(layer "B.Fab")
		)
		(fp_line
			(start -0.120396 0.2794)
			(end 0.12065 0.2794)
			(stroke
				(width 0.1)
				(type default)
			)
			(layer "B.Fab")
		)
		(fp_line
			(start 0.67945 0.3048)
			(end 0.67945 -0.305054)
			(stroke
				(width 0.1)
				(type default)
			)
			(layer "B.Fab")
		)
		(fp_line
			(start 0.12065 0.3048)
			(end 0.67945 0.3048)
			(stroke
				(width 0.1)
				(type default)
			)
			(layer "B.Fab")
		)
		(fp_line
			(start -0.120396 0.3048)
			(end -0.120396 0.2794)
			(stroke
				(width 0.1)
				(type default)
			)
			(layer "B.Fab")
		)
		(fp_line
			(start -0.67945 0.3048)
			(end -0.120396 0.3048)
			(stroke
				(width 0.1)
				(type default)
			)
			(layer "B.Fab")
		)
		(pad "1" smd circle
			(at 0.40005 0 270)
			(size 0 0)
			(layers "B.Cu" "B.Mask" "B.Paste")
			(net "PWRGD_FAIL_CPU1_AB_R1")
		)
		(pad "2" smd circle
			(at -0.40005 0 270)
			(size 0 0)
			(layers "B.Cu" "B.Mask" "B.Paste")
			(net "PWRGD_FAIL_CPU1_AB_R")
		)
	)
)
